(kicad_pcb
	(version 20260206)
	(generator "pcbnew")
	(generator_version "10.0")
	(general
		(thickness 1.6)
		(legacy_teardrops no)
	)
	(paper "A4")
	(title_block
		(title "9054_F0T_PDB_BD_GPU_F_V04_1213_1550_OCP.brd")
		(comment 1 "Grand Teton / footprints 393-398 of 608")
	)
	(layers
		(0 "F.Cu" signal "TOP")
		(4 "In1.Cu" signal "GND")
		(6 "In2.Cu" signal "IN1")
		(8 "In3.Cu" signal "GND1")
		(10 "In4.Cu" signal "VCC")
		(12 "In5.Cu" signal "VCC1")
		(14 "In6.Cu" signal "GND2")
		(16 "In7.Cu" signal "IN2")
		(18 "In8.Cu" signal "GND3")
		(2 "B.Cu" signal "BOTTOM")
		(9 "F.Adhes" user "F.Adhesive")
		(11 "B.Adhes" user "B.Adhesive")
		(13 "F.Paste" user "Package Geometry/Pastemask Top")
		(15 "B.Paste" user "Package Geometry/Pastemask Bottom")
		(5 "F.SilkS" user "Ref Des/Silkscreen Top")
		(7 "B.SilkS" user "Ref Des/Silkscreen Bottom")
		(1 "F.Mask" user "Board Geometry/Soldermask Top")
		(3 "B.Mask" user "Board Geometry/Soldermask Bottom")
		(17 "Dwgs.User" user "User.Drawings")
		(19 "Cmts.User" user "User.Comments")
		(21 "Eco1.User" user "User.Eco1")
		(23 "Eco2.User" user "User.Eco2")
		(25 "Edge.Cuts" user "Board Geometry/Outline")
		(27 "Margin" user)
		(31 "F.CrtYd" user "Package Geometry/Place Bound Top")
		(29 "B.CrtYd" user "Package Geometry/Place Bound Bottom")
		(35 "F.Fab" user "Ref Des/Assembly Top")
		(33 "B.Fab" user "Ref Des/Assembly Bottom")
	)
	(footprint ""
		(layer "B.Cu")
		(at 179.9844 -49.022 -90)
		(property "Reference" "R5893"
			(at 0 0 90)
			(layer "B.SilkS")
			(hide yes)
			(effects
				(font
					(size 1.27 1.27)
				)
				(justify mirror)
			)
		)
		(property "Value" ""
			(at 0 0 90)
			(layer "B.Fab")
			(effects
				(font
					(size 1.27 1.27)
				)
				(justify mirror)
			)
		)
		(duplicate_pad_numbers_are_jumpers no)
		(fp_line
			(start -1.651 0.8382)
			(end 1.651 0.8382)
			(stroke
				(width 0.1524)
				(type default)
			)
			(layer "B.SilkS")
		)
		(fp_line
			(start 1.651 0.8382)
			(end 1.651 -0.8382)
			(stroke
				(width 0.1524)
				(type default)
			)
			(layer "B.SilkS")
		)
		(fp_line
			(start -1.651 -0.8382)
			(end -1.651 0.8382)
			(stroke
				(width 0.1524)
				(type default)
			)
			(layer "B.SilkS")
		)
		(fp_line
			(start 1.651 -0.8382)
			(end -1.651 -0.8382)
			(stroke
				(width 0.1524)
				(type default)
			)
			(layer "B.SilkS")
		)
		(fp_line
			(start -1.560576 0.7366)
			(end -1.560576 -0.7366)
			(stroke
				(width 0.1)
				(type default)
			)
			(layer "B.Fab")
		)
		(fp_line
			(start -1.524 0.7366)
			(end -1.560576 0.7366)
			(stroke
				(width 0.1)
				(type default)
			)
			(layer "B.Fab")
		)
		(fp_line
			(start 1.524 0.7366)
			(end -1.524 0.7366)
			(stroke
				(width 0.1)
				(type default)
			)
			(layer "B.Fab")
		)
		(fp_line
			(start 1.559814 0.7366)
			(end 1.524 0.7366)
			(stroke
				(width 0.1)
				(type default)
			)
			(layer "B.Fab")
		)
		(fp_line
			(start -1.560576 -0.7366)
			(end -1.524 -0.7366)
			(stroke
				(width 0.1)
				(type default)
			)
			(layer "B.Fab")
		)
		(fp_line
			(start -1.524 -0.7366)
			(end 1.524 -0.7366)
			(stroke
				(width 0.1)
				(type default)
			)
			(layer "B.Fab")
		)
		(fp_line
			(start 1.524 -0.7366)
			(end 1.559814 -0.7366)
			(stroke
				(width 0.1)
				(type default)
			)
			(layer "B.Fab")
		)
		(fp_line
			(start 1.559814 -0.7366)
			(end 1.559814 0.7366)
			(stroke
				(width 0.1)
				(type default)
			)
			(layer "B.Fab")
		)
		(pad "1" smd rect
			(at 0.94996 0 270)
			(size 1.1176 1.3716)
			(layers "B.Cu" "B.Mask" "B.Paste")
			(net "P52V_2_FUSE_1")
		)
		(pad "2" smd rect
			(at -0.94996 0 270)
			(size 1.1176 1.3716)
			(layers "B.Cu" "B.Mask" "B.Paste")
			(net "FM_HS2_EN_FUSE")
		)
	)
	(footprint ""
		(layer "B.Cu")
		(at 156.637736 -79.375 -90)
		(property "Reference" "R5876"
			(at 0 0 90)
			(layer "B.SilkS")
			(hide yes)
			(effects
				(font
					(size 1.27 1.27)
				)
				(justify mirror)
			)
		)
		(property "Value" ""
			(at 0 0 90)
			(layer "B.Fab")
			(effects
				(font
					(size 1.27 1.27)
				)
				(justify mirror)
			)
		)
		(duplicate_pad_numbers_are_jumpers no)
		(fp_line
			(start -0.7874 0.4064)
			(end 0.7874 0.4064)
			(stroke
				(width 0.1524)
				(type default)
			)
			(layer "B.SilkS")
		)
		(fp_line
			(start 0.7874 0.4064)
			(end 0.7874 -0.4064)
			(stroke
				(width 0.1524)
				(type default)
			)
			(layer "B.SilkS")
		)
		(fp_line
			(start -0.7874 -0.4064)
			(end -0.7874 0.4064)
			(stroke
				(width 0.1524)
				(type default)
			)
			(layer "B.SilkS")
		)
		(fp_line
			(start 0.7874 -0.4064)
			(end -0.7874 -0.4064)
			(stroke
				(width 0.1524)
				(type default)
			)
			(layer "B.SilkS")
		)
		(fp_line
			(start -0.67945 0.3048)
			(end -0.120396 0.3048)
			(stroke
				(width 0.1)
				(type default)
			)
			(layer "B.Fab")
		)
		(fp_line
			(start -0.120396 0.3048)
			(end -0.120396 0.2794)
			(stroke
				(width 0.1)
				(type default)
			)
			(layer "B.Fab")
		)
		(fp_line
			(start 0.12065 0.3048)
			(end 0.67945 0.3048)
			(stroke
				(width 0.1)
				(type default)
			)
			(layer "B.Fab")
		)
		(fp_line
			(start 0.67945 0.3048)
			(end 0.67945 -0.305054)
			(stroke
				(width 0.1)
				(type default)
			)
			(layer "B.Fab")
		)
		(fp_line
			(start -0.120396 0.2794)
			(end 0.12065 0.2794)
			(stroke
				(width 0.1)
				(type default)
			)
			(layer "B.Fab")
		)
		(fp_line
			(start 0.12065 0.2794)
			(end 0.12065 0.3048)
			(stroke
				(width 0.1)
				(type default)
			)
			(layer "B.Fab")
		)
		(fp_line
			(start -0.12065 -0.2794)
			(end -0.12065 -0.3048)
			(stroke
				(width 0.1)
				(type default)
			)
			(layer "B.Fab")
		)
		(fp_line
			(start 0.12065 -0.2794)
			(end -0.12065 -0.2794)
			(stroke
				(width 0.1)
				(type default)
			)
			(layer "B.Fab")
		)
		(fp_line
			(start -0.67945 -0.3048)
			(end -0.67945 0.3048)
			(stroke
				(width 0.1)
				(type default)
			)
			(layer "B.Fab")
		)
		(fp_line
			(start -0.12065 -0.3048)
			(end -0.67945 -0.3048)
			(stroke
				(width 0.1)
				(type default)
			)
			(layer "B.Fab")
		)
		(fp_line
			(start 0.12065 -0.305054)
			(end 0.12065 -0.2794)
			(stroke
				(width 0.1)
				(type default)
			)
			(layer "B.Fab")
		)
		(fp_line
			(start 0.67945 -0.305054)
			(end 0.12065 -0.305054)
			(stroke
				(width 0.1)
				(type default)
			)
			(layer "B.Fab")
		)
		(pad "1" smd circle
			(at 0.40005 0 90)
			(size 0 0)
			(layers "B.Cu" "B.Mask" "B.Paste")
			(net "P52V_HS2_ADR1")
		)
		(pad "2" smd circle
			(at -0.40005 0 90)
			(size 0 0)
			(layers "B.Cu" "B.Mask" "B.Paste")
			(net "GND1_FIELD_SIGNAL")
		)
	)
	(footprint ""
		(layer "B.Cu")
		(at 278.4094 -66.929)
		(property "Reference" "R147"
			(at 0 0 0)
			(layer "B.SilkS")
			(hide yes)
			(effects
				(font
					(size 1.27 1.27)
				)
				(justify mirror)
			)
		)
		(property "Value" ""
			(at 0 0 0)
			(layer "B.Fab")
			(effects
				(font
					(size 1.27 1.27)
				)
				(justify mirror)
			)
		)
		(duplicate_pad_numbers_are_jumpers no)
		(fp_line
			(start -0.7874 -0.4064)
			(end -0.7874 0.4064)
			(stroke
				(width 0.1524)
				(type default)
			)
			(layer "B.SilkS")
		)
		(fp_line
			(start -0.7874 0.4064)
			(end 0.7874 0.4064)
			(stroke
				(width 0.1524)
				(type default)
			)
			(layer "B.SilkS")
		)
		(fp_line
			(start 0.7874 -0.4064)
			(end -0.7874 -0.4064)
			(stroke
				(width 0.1524)
				(type default)
			)
			(layer "B.SilkS")
		)
		(fp_line
			(start 0.7874 0.4064)
			(end 0.7874 -0.4064)
			(stroke
				(width 0.1524)
				(type default)
			)
			(layer "B.SilkS")
		)
		(fp_line
			(start -0.67945 -0.3048)
			(end -0.67945 0.3048)
			(stroke
				(width 0.1)
				(type default)
			)
			(layer "B.Fab")
		)
		(fp_line
			(start -0.67945 0.3048)
			(end -0.120396 0.3048)
			(stroke
				(width 0.1)
				(type default)
			)
			(layer "B.Fab")
		)
		(fp_line
			(start -0.12065 -0.3048)
			(end -0.67945 -0.3048)
			(stroke
				(width 0.1)
				(type default)
			)
			(layer "B.Fab")
		)
		(fp_line
			(start -0.12065 -0.2794)
			(end -0.12065 -0.3048)
			(stroke
				(width 0.1)
				(type default)
			)
			(layer "B.Fab")
		)
		(fp_line
			(start -0.120396 0.2794)
			(end 0.12065 0.2794)
			(stroke
				(width 0.1)
				(type default)
			)
			(layer "B.Fab")
		)
		(fp_line
			(start -0.120396 0.3048)
			(end -0.120396 0.2794)
			(stroke
				(width 0.1)
				(type default)
			)
			(layer "B.Fab")
		)
		(fp_line
			(start 0.12065 -0.305054)
			(end 0.12065 -0.2794)
			(stroke
				(width 0.1)
				(type default)
			)
			(layer "B.Fab")
		)
		(fp_line
			(start 0.12065 -0.2794)
			(end -0.12065 -0.2794)
			(stroke
				(width 0.1)
				(type default)
			)
			(layer "B.Fab")
		)
		(fp_line
			(start 0.12065 0.2794)
			(end 0.12065 0.3048)
			(stroke
				(width 0.1)
				(type default)
			)
			(layer "B.Fab")
		)
		(fp_line
			(start 0.12065 0.3048)
			(end 0.67945 0.3048)
			(stroke
				(width 0.1)
				(type default)
			)
			(layer "B.Fab")
		)
		(fp_line
			(start 0.67945 -0.305054)
			(end 0.12065 -0.305054)
			(stroke
				(width 0.1)
				(type default)
			)
			(layer "B.Fab")
		)
		(fp_line
			(start 0.67945 0.3048)
			(end 0.67945 -0.305054)
			(stroke
				(width 0.1)
				(type default)
			)
			(layer "B.Fab")
		)
		(pad "1" smd circle
			(at 0.40005 0 180)
			(size 0 0)
			(layers "B.Cu" "B.Mask" "B.Paste")
			(net "P3V3_AUX")
		)
		(pad "2" smd circle
			(at -0.40005 0 180)
			(size 0 0)
			(layers "B.Cu" "B.Mask" "B.Paste")
			(net "SMB_P52V_PDB_SDA")
		)
	)
	(footprint ""
		(layer "B.Cu")
		(at 108.7374 -55.626 -90)
		(property "Reference" "PD17"
			(at 3.46837 -1.0668 0)
			(unlocked yes)
			(layer "B.SilkS")
			(effects
				(font
					(size 0.7874 0.5842)
					(thickness 0.1524)
				)
				(justify left mirror)
			)
		)
		(property "Value" ""
			(at 0 0 90)
			(layer "B.Fab")
			(effects
				(font
					(size 1.27 1.27)
				)
				(justify mirror)
			)
		)
		(duplicate_pad_numbers_are_jumpers no)
		(fp_line
			(start -2.032 0.7112)
			(end 1.651 0.7112)
			(stroke
				(width 0.1524)
				(type default)
			)
			(layer "B.SilkS")
		)
		(fp_line
			(start 1.651 0.7112)
			(end 1.651 -0.7112)
			(stroke
				(width 0.1524)
				(type default)
			)
			(layer "B.SilkS")
		)
		(fp_line
			(start -1.778 0.6858)
			(end -1.778 -0.6858)
			(stroke
				(width 0.1524)
				(type default)
			)
			(layer "B.SilkS")
		)
		(fp_line
			(start 0.299974 0.500126)
			(end -0.199898 0)
			(stroke
				(width 0.1524)
				(type default)
			)
			(layer "B.SilkS")
		)
		(fp_line
			(start -0.199898 0)
			(end 0.299974 -0.500126)
			(stroke
				(width 0.1524)
				(type default)
			)
			(layer "B.SilkS")
		)
		(fp_line
			(start -0.299974 -0.500126)
			(end -0.299974 0.500126)
			(stroke
				(width 0.1524)
				(type default)
			)
			(layer "B.SilkS")
		)
		(fp_line
			(start 0.299974 -0.500126)
			(end 0.299974 0.500126)
			(stroke
				(width 0.1524)
				(type default)
			)
			(layer "B.SilkS")
		)
		(fp_line
			(start -1.905 -0.6858)
			(end -1.905 0.6858)
			(stroke
				(width 0.1524)
				(type default)
			)
			(layer "B.SilkS")
		)
		(fp_line
			(start -1.651 -0.6858)
			(end -1.651 0.6858)
			(stroke
				(width 0.1524)
				(type default)
			)
			(layer "B.SilkS")
		)
		(fp_line
			(start -2.032 -0.7112)
			(end -2.032 0.7112)
			(stroke
				(width 0.1524)
				(type default)
			)
			(layer "B.SilkS")
		)
		(fp_line
			(start 1.651 -0.7112)
			(end -2.032 -0.7112)
			(stroke
				(width 0.1524)
				(type default)
			)
			(layer "B.SilkS")
		)
		(fp_line
			(start -0.899922 0.700024)
			(end 0.899922 0.700024)
			(stroke
				(width 0.1)
				(type default)
			)
			(layer "B.Fab")
		)
		(fp_line
			(start 0.899922 0.700024)
			(end 0.899922 0.175006)
			(stroke
				(width 0.1)
				(type default)
			)
			(layer "B.Fab")
		)
		(fp_line
			(start 0.299974 0.500126)
			(end -0.199898 0)
			(stroke
				(width 0.1)
				(type default)
			)
			(layer "B.Fab")
		)
		(fp_line
			(start -1.35001 0.175006)
			(end -0.899922 0.175006)
			(stroke
				(width 0.1)
				(type default)
			)
			(layer "B.Fab")
		)
		(fp_line
			(start -0.899922 0.175006)
			(end -0.899922 0.700024)
			(stroke
				(width 0.1)
				(type default)
			)
			(layer "B.Fab")
		)
		(fp_line
			(start 0.899922 0.175006)
			(end 1.35001 0.175006)
			(stroke
				(width 0.1)
				(type default)
			)
			(layer "B.Fab")
		)
		(fp_line
			(start 1.35001 0.175006)
			(end 1.35001 -0.225044)
			(stroke
				(width 0.1)
				(type default)
			)
			(layer "B.Fab")
		)
		(fp_line
			(start -0.199898 0)
			(end 0.299974 -0.500126)
			(stroke
				(width 0.1)
				(type default)
			)
			(layer "B.Fab")
		)
		(fp_line
			(start -1.35001 -0.225044)
			(end -1.35001 0.175006)
			(stroke
				(width 0.1)
				(type default)
			)
			(layer "B.Fab")
		)
		(fp_line
			(start -0.899922 -0.225044)
			(end -1.35001 -0.225044)
			(stroke
				(width 0.1)
				(type default)
			)
			(layer "B.Fab")
		)
		(fp_line
			(start 0.899922 -0.225044)
			(end 0.899922 -0.700024)
			(stroke
				(width 0.1)
				(type default)
			)
			(layer "B.Fab")
		)
		(fp_line
			(start 1.35001 -0.225044)
			(end 0.899922 -0.225044)
			(stroke
				(width 0.1)
				(type default)
			)
			(layer "B.Fab")
		)
		(fp_line
			(start -0.299974 -0.500126)
			(end -0.299974 0.500126)
			(stroke
				(width 0.1)
				(type default)
			)
			(layer "B.Fab")
		)
		(fp_line
			(start 0.299974 -0.500126)
			(end 0.299974 0.500126)
			(stroke
				(width 0.1)
				(type default)
			)
			(layer "B.Fab")
		)
		(fp_line
			(start -0.899922 -0.700024)
			(end -0.899922 -0.225044)
			(stroke
				(width 0.1)
				(type default)
			)
			(layer "B.Fab")
		)
		(fp_line
			(start 0.899922 -0.700024)
			(end -0.899922 -0.700024)
			(stroke
				(width 0.1)
				(type default)
			)
			(layer "B.Fab")
		)
		(fp_text user "+"
			(at 2.8956 -0.01905 270)
			(unlocked yes)
			(layer "B.SilkS")
			(effects
				(font
					(size 1.905 1.4224)
					(thickness 0.1524)
				)
				(justify left mirror)
			)
		)
		(fp_text user "-"
			(at -1.8288 -0.24765 270)
			(unlocked yes)
			(layer "B.SilkS")
			(effects
				(font
					(size 1.905 1.4224)
					(thickness 0.1524)
				)
				(justify left mirror)
			)
		)
		(fp_text user "+"
			(at 2.794 -0.19685 270)
			(unlocked yes)
			(layer "B.Fab")
			(effects
				(font
					(size 1.905 1.4224)
					(thickness 0.1524)
				)
				(justify left mirror)
			)
		)
		(fp_text user "-"
			(at -1.8288 -0.24765 270)
			(unlocked yes)
			(layer "B.Fab")
			(effects
				(font
					(size 1.905 1.4224)
					(thickness 0.1524)
				)
				(justify left mirror)
			)
		)
		(pad "1" smd rect
			(at 1.0922 0 270)
			(size 0.8128 0.8636)
			(layers "B.Cu" "B.Mask" "B.Paste")
			(net "P52V_HS2_4287_GATE_R")
		)
		(pad "2" smd rect
			(at -1.0922 0 90)
			(size 0.8128 0.8636)
			(layers "B.Cu" "B.Mask" "B.Paste")
			(net "P52V_HS2_GATE_R1")
		)
	)
	(footprint ""
		(layer "B.Cu")
		(at 278.4094 -61.849)
		(property "Reference" "R150"
			(at 0 0 0)
			(layer "B.SilkS")
			(hide yes)
			(effects
				(font
					(size 1.27 1.27)
				)
				(justify mirror)
			)
		)
		(property "Value" ""
			(at 0 0 0)
			(layer "B.Fab")
			(effects
				(font
					(size 1.27 1.27)
				)
				(justify mirror)
			)
		)
		(duplicate_pad_numbers_are_jumpers no)
		(fp_line
			(start -0.7874 -0.4064)
			(end -0.7874 0.4064)
			(stroke
				(width 0.1524)
				(type default)
			)
			(layer "B.SilkS")
		)
		(fp_line
			(start -0.7874 0.4064)
			(end 0.7874 0.4064)
			(stroke
				(width 0.1524)
				(type default)
			)
			(layer "B.SilkS")
		)
		(fp_line
			(start 0.7874 -0.4064)
			(end -0.7874 -0.4064)
			(stroke
				(width 0.1524)
				(type default)
			)
			(layer "B.SilkS")
		)
		(fp_line
			(start 0.7874 0.4064)
			(end 0.7874 -0.4064)
			(stroke
				(width 0.1524)
				(type default)
			)
			(layer "B.SilkS")
		)
		(fp_line
			(start -0.67945 -0.3048)
			(end -0.67945 0.3048)
			(stroke
				(width 0.1)
				(type default)
			)
			(layer "B.Fab")
		)
		(fp_line
			(start -0.67945 0.3048)
			(end -0.120396 0.3048)
			(stroke
				(width 0.1)
				(type default)
			)
			(layer "B.Fab")
		)
		(fp_line
			(start -0.12065 -0.3048)
			(end -0.67945 -0.3048)
			(stroke
				(width 0.1)
				(type default)
			)
			(layer "B.Fab")
		)
		(fp_line
			(start -0.12065 -0.2794)
			(end -0.12065 -0.3048)
			(stroke
				(width 0.1)
				(type default)
			)
			(layer "B.Fab")
		)
		(fp_line
			(start -0.120396 0.2794)
			(end 0.12065 0.2794)
			(stroke
				(width 0.1)
				(type default)
			)
			(layer "B.Fab")
		)
		(fp_line
			(start -0.120396 0.3048)
			(end -0.120396 0.2794)
			(stroke
				(width 0.1)
				(type default)
			)
			(layer "B.Fab")
		)
		(fp_line
			(start 0.12065 -0.305054)
			(end 0.12065 -0.2794)
			(stroke
				(width 0.1)
				(type default)
			)
			(layer "B.Fab")
		)
		(fp_line
			(start 0.12065 -0.2794)
			(end -0.12065 -0.2794)
			(stroke
				(width 0.1)
				(type default)
			)
			(layer "B.Fab")
		)
		(fp_line
			(start 0.12065 0.2794)
			(end 0.12065 0.3048)
			(stroke
				(width 0.1)
				(type default)
			)
			(layer "B.Fab")
		)
		(fp_line
			(start 0.12065 0.3048)
			(end 0.67945 0.3048)
			(stroke
				(width 0.1)
				(type default)
			)
			(layer "B.Fab")
		)
		(fp_line
			(start 0.67945 -0.305054)
			(end 0.12065 -0.305054)
			(stroke
				(width 0.1)
				(type default)
			)
			(layer "B.Fab")
		)
		(fp_line
			(start 0.67945 0.3048)
			(end 0.67945 -0.305054)
			(stroke
				(width 0.1)
				(type default)
			)
			(layer "B.Fab")
		)
		(pad "1" smd circle
			(at 0.40005 0 180)
			(size 0 0)
			(layers "B.Cu" "B.Mask" "B.Paste")
			(net "P3V3_AUX")
		)
		(pad "2" smd circle
			(at -0.40005 0 180)
			(size 0 0)
			(layers "B.Cu" "B.Mask" "B.Paste")
			(net "P52V_HS1_GPO2")
		)
	)
	(footprint ""
		(layer "B.Cu")
		(at 171.115736 -56.007 -90)
		(property "Reference" "PR6977"
			(at 0 0 90)
			(layer "B.SilkS")
			(hide yes)
			(effects
				(font
					(size 1.27 1.27)
				)
				(justify mirror)
			)
		)
		(property "Value" ""
			(at 0 0 90)
			(layer "B.Fab")
			(effects
				(font
					(size 1.27 1.27)
				)
				(justify mirror)
			)
		)
		(duplicate_pad_numbers_are_jumpers no)
		(fp_line
			(start -1.651 0.8382)
			(end 1.651 0.8382)
			(stroke
				(width 0.1524)
				(type default)
			)
			(layer "B.SilkS")
		)
		(fp_line
			(start 1.651 0.8382)
			(end 1.651 -0.8382)
			(stroke
				(width 0.1524)
				(type default)
			)
			(layer "B.SilkS")
		)
		(fp_line
			(start -1.651 -0.8382)
			(end -1.651 0.8382)
			(stroke
				(width 0.1524)
				(type default)
			)
			(layer "B.SilkS")
		)
		(fp_line
			(start 1.651 -0.8382)
			(end -1.651 -0.8382)
			(stroke
				(width 0.1524)
				(type default)
			)
			(layer "B.SilkS")
		)
		(fp_line
			(start -1.560576 0.7366)
			(end -1.560576 -0.7366)
			(stroke
				(width 0.1)
				(type default)
			)
			(layer "B.Fab")
		)
		(fp_line
			(start -1.524 0.7366)
			(end -1.560576 0.7366)
			(stroke
				(width 0.1)
				(type default)
			)
			(layer "B.Fab")
		)
		(fp_line
			(start 1.524 0.7366)
			(end -1.524 0.7366)
			(stroke
				(width 0.1)
				(type default)
			)
			(layer "B.Fab")
		)
		(fp_line
			(start 1.559814 0.7366)
			(end 1.524 0.7366)
			(stroke
				(width 0.1)
				(type default)
			)
			(layer "B.Fab")
		)
		(fp_line
			(start -1.560576 -0.7366)
			(end -1.524 -0.7366)
			(stroke
				(width 0.1)
				(type default)
			)
			(layer "B.Fab")
		)
		(fp_line
			(start -1.524 -0.7366)
			(end 1.524 -0.7366)
			(stroke
				(width 0.1)
				(type default)
			)
			(layer "B.Fab")
		)
		(fp_line
			(start 1.524 -0.7366)
			(end 1.559814 -0.7366)
			(stroke
				(width 0.1)
				(type default)
			)
			(layer "B.Fab")
		)
		(fp_line
			(start 1.559814 -0.7366)
			(end 1.559814 0.7366)
			(stroke
				(width 0.1)
				(type default)
			)
			(layer "B.Fab")
		)
		(pad "1" smd rect
			(at 0.94996 0 270)
			(size 1.1176 1.3716)
			(layers "B.Cu" "B.Mask" "B.Paste")
			(net "P52V_2")
		)
		(pad "2" smd rect
			(at -0.94996 0 270)
			(size 1.1176 1.3716)
			(layers "B.Cu" "B.Mask" "B.Paste")
			(net "P52V_HS2_OV")
		)
	)
)
